#ISCELL
  mstr_symbols cad_note *
  *
#ISCELL
  mstr_symbols design_note *
  *
#ISCELL
  mstr_symbols intel_corp_bpage *
  *
#CELL
  dev_discrete cap_a *
  page163_i10
#ISCELL
  mstr_symbols gnd *
  page163_i11
#CELL
  dev_discrete cap_a *
  page163_i12
#ISCELL
  mstr_symbols gnd *
  page163_i13
#CELL
  mstr_discrete res *
  page163_i15
#CELL
  mstr_discrete res *
  page163_i16
#ISCELL
  mstr_standard offpage *
  page163_i18
#ISCELL
  mstr_standard offpage *
  page163_i19
#CELL
  mstr_discrete res *
  page163_i2
#CELL
  mstr_discrete res *
  page163_i20
#CELL
  mstr_discrete res *
  page163_i21
#ISCELL
  mstr_symbols p3v3_stby *
  page163_i26
#ISCELL
  mstr_symbols p3v3_stby *
  page163_i27
#CELL
  w_hdl tca9517dgkr-gp *
  page163_i28
#ISCELL
  mstr_symbols gnd *
  page163_i29
#CELL
  mstr_discrete res *
  page163_i3
#ISCELL
  mstr_standard offpage *
  page163_i4
#ISCELL
  mstr_standard offpage *
  page163_i5
#CELL
  mstr_discrete res *
  page163_i6
#CELL
  mstr_discrete res *
  page163_i7
#ISCELL
  mstr_symbols pvccio_cpu1 *
  page163_i8
#ISCELL
  mstr_symbols pvccio_cpu1 *
  page163_i9
